# Data Center RDIMM DDR4 Tester — symbol library table
(sym_lib_table
  (lib (name "data-center-rdimm-ddr4-tester")(type "KiCad")(uri "${KIPRJMOD}/lib/data-center-rdimm-ddr4-tester.kicad_sym")(options "")(descr ""))
)
